(kicad_pcb
	(version 20241229)
	(generator "pcbnew")
	(generator_version "9.0")
	(general
		(thickness 1.711)
		(legacy_teardrops no)
	)
	(paper "A4")
	(title_block
		(title "Antmicro Baseboard for Jetson AGX Thor")
		(date "2026-02-18")
		(rev "1.1.0")
		(company "Antmicro Ltd")
		(comment 1 "www.antmicro.com")
		(comment 9 "footprints 205-208 of 1170")
	)
	(layers
		(0 "F.Cu" signal)
		(4 "In1.Cu" signal)
		(6 "In2.Cu" signal)
		(8 "In3.Cu" signal)
		(10 "In4.Cu" jumper)
		(12 "In5.Cu" signal)
		(14 "In6.Cu" signal)
		(16 "In7.Cu" signal)
		(18 "In8.Cu" signal)
		(2 "B.Cu" signal)
		(9 "F.Adhes" user "F.Adhesive")
		(11 "B.Adhes" user "B.Adhesive")
		(13 "F.Paste" user)
		(15 "B.Paste" user)
		(5 "F.SilkS" user "F.Silkscreen")
		(7 "B.SilkS" user "B.Silkscreen")
		(1 "F.Mask" user)
		(3 "B.Mask" user)
		(17 "Dwgs.User" user "User.Drawings")
		(19 "Cmts.User" user "User.Comments")
		(21 "Eco1.User" user "User.Eco1")
		(23 "Eco2.User" user "User.Eco2")
		(25 "Edge.Cuts" user)
		(27 "Margin" user)
		(31 "F.CrtYd" user "F.Courtyard")
		(29 "B.CrtYd" user "B.Courtyard")
		(35 "F.Fab" user)
		(33 "B.Fab" user)
	)
	(footprint "antmicro-footprints:USON-10_2.5x1mm_P0.5mm"
		(layer "F.Cu")
		(at 221.404132 89.587)
		(descr "USON-10 2.5x1mm_ Pitch 0.5mm")
		(tags "USON-10 2.5x1mm Pitch 0.5mm")
		(property "Reference" "U38"
			(at 1.928 1.005 90)
			(layer "F.SilkS")
			(effects
				(font
					(size 0.7 0.7)
					(thickness 0.15)
				)
				(justify left bottom)
			)
		)
		(property "Value" "TPD4E05U06QDQARQ1"
			(at 0.018 2.499 0)
			(layer "F.Fab")
			(effects
				(font
					(size 0.7 0.7)
					(thickness 0.15)
				)
				(justify left bottom)
			)
		)
		(property "Datasheet" "https://www.ti.com/lit/ds/symlink/tpd4e05u06-q1.pdf?HQS=dis-mous-null-mousermode-dsf-pf-null-wwe&ts=1663591265741&ref_url=https%253A%252F%252Fwww.mouser.com%252F"
			(at 0 0 0)
			(layer "F.Fab")
			(hide yes)
			(effects
				(font
					(size 1.27 1.27)
					(thickness 0.15)
				)
			)
		)
		(property "Description" "TVS diode array, 12 kV, USON-10, 5.5 V, 0.5 pF"
			(at 0 0 0)
			(layer "F.Fab")
			(hide yes)
			(effects
				(font
					(size 1.27 1.27)
					(thickness 0.15)
				)
			)
		)
		(property "Manufacturer" "Texas Instruments"
			(at 0 0 0)
			(unlocked yes)
			(layer "F.Fab")
			(hide yes)
			(effects
				(font
					(size 1 1)
					(thickness 0.15)
				)
			)
		)
		(property "MPN" "TPD4E05U06QDQARQ1"
			(at 0 0 0)
			(unlocked yes)
			(layer "F.Fab")
			(hide yes)
			(effects
				(font
					(size 1 1)
					(thickness 0.15)
				)
			)
		)
		(property "Author" "Antmicro"
			(at 0 0 0)
			(unlocked yes)
			(layer "F.Fab")
			(hide yes)
			(effects
				(font
					(size 1 1)
					(thickness 0.15)
				)
			)
		)
		(property "License" "Apache-2.0"
			(at 0 0 0)
			(unlocked yes)
			(layer "F.Fab")
			(hide yes)
			(effects
				(font
					(size 1 1)
					(thickness 0.15)
				)
			)
		)
		(sheetname "/USB DP Alt mode/")
		(sheetfile "usb_dp.kicad_sch")
		(attr smd)
		(fp_line
			(start 0.498 -1.401)
			(end -0.5 -1.401)
			(stroke
				(width 0.15)
				(type solid)
			)
			(layer "F.SilkS")
		)
		(fp_line
			(start 0.498 1.398)
			(end -0.5 1.398)
			(stroke
				(width 0.15)
				(type solid)
			)
			(layer "F.SilkS")
		)
		(fp_circle
			(center -0.68 -1.27)
			(end -0.63 -1.27)
			(stroke
				(width 0.15)
				(type solid)
			)
			(fill yes)
			(layer "F.SilkS")
		)
		(fp_rect
			(start -0.8 -1.5)
			(end 0.8 1.499)
			(stroke
				(width 0.05)
				(type solid)
			)
			(fill no)
			(layer "F.CrtYd")
		)
		(fp_line
			(start -0.5 -1)
			(end -0.5 1.249)
			(stroke
				(width 0.15)
				(type solid)
			)
			(layer "F.Fab")
		)
		(fp_line
			(start -0.5 1.249)
			(end 0.498 1.249)
			(stroke
				(width 0.15)
				(type solid)
			)
			(layer "F.Fab")
		)
		(fp_line
			(start -0.25 -1.25)
			(end -0.5 -1)
			(stroke
				(width 0.15)
				(type solid)
			)
			(layer "F.Fab")
		)
		(fp_line
			(start 0.498 -1.25)
			(end -0.25 -1.25)
			(stroke
				(width 0.15)
				(type solid)
			)
			(layer "F.Fab")
		)
		(fp_line
			(start 0.498 -1.25)
			(end 0.498 1.249)
			(stroke
				(width 0.15)
				(type solid)
			)
			(layer "F.Fab")
		)
		(fp_text user "Author: Antmicro"
			(at -0.802 5.7 0)
			(layer "F.Fab")
			(effects
				(font
					(size 0.7 0.7)
					(thickness 0.15)
				)
				(justify left bottom)
			)
		)
		(fp_text user "License: Apache-2.0"
			(at -0.802 6.9 0)
			(layer "F.Fab")
			(effects
				(font
					(size 0.7 0.7)
					(thickness 0.15)
				)
				(justify left bottom)
			)
		)
		(fp_text user "${REFERENCE}"
			(at -0.802 4.498 0)
			(layer "F.Fab")
			(effects
				(font
					(size 0.7 0.7)
					(thickness 0.15)
				)
				(justify left bottom)
			)
		)
		(pad "1" smd roundrect
			(at -0.387 -1 270)
			(size 0.25 0.55)
			(layers "F.Cu" "F.Mask" "F.Paste")
			(roundrect_rratio 0.25)
			(net 140 "/SoM_IO2/USB1.D-")
			(pintype "passive")
		)
		(pad "2" smd roundrect
			(at -0.387 -0.5 270)
			(size 0.25 0.55)
			(layers "F.Cu" "F.Mask" "F.Paste")
			(roundrect_rratio 0.25)
			(net 55 "/SoM_IO2/USB1.D+")
			(pintype "passive")
		)
		(pad "3" smd roundrect
			(at -0.387 0 270)
			(size 0.4 0.55)
			(layers "F.Cu" "F.Mask" "F.Paste")
			(roundrect_rratio 0.25)
			(net 1 "GND")
			(pintype "power_in")
		)
		(pad "4" smd roundrect
			(at -0.387 0.498 270)
			(size 0.25 0.55)
			(layers "F.Cu" "F.Mask" "F.Paste")
			(roundrect_rratio 0.25)
			(net 816 "/USB DP Alt mode/USBC1_CC2")
			(pintype "passive")
		)
		(pad "5" smd roundrect
			(at -0.387 0.998 270)
			(size 0.25 0.55)
			(layers "F.Cu" "F.Mask" "F.Paste")
			(roundrect_rratio 0.25)
			(net 817 "/USB DP Alt mode/USBC1_CC1")
			(pintype "passive")
		)
		(pad "6" smd roundrect
			(at 0.385 0.998 270)
			(size 0.25 0.55)
			(layers "F.Cu" "F.Mask" "F.Paste")
			(roundrect_rratio 0.25)
			(net 817 "/USB DP Alt mode/USBC1_CC1")
			(pintype "passive")
		)
		(pad "7" smd roundrect
			(at 0.385 0.498 270)
			(size 0.25 0.55)
			(layers "F.Cu" "F.Mask" "F.Paste")
			(roundrect_rratio 0.25)
			(net 816 "/USB DP Alt mode/USBC1_CC2")
			(pintype "passive")
		)
		(pad "8" smd roundrect
			(at 0.385 0 270)
			(size 0.4 0.55)
			(layers "F.Cu" "F.Mask" "F.Paste")
			(roundrect_rratio 0.25)
			(net 1 "GND")
			(pintype "passive")
		)
		(pad "9" smd roundrect
			(at 0.385 -0.5 270)
			(size 0.25 0.55)
			(layers "F.Cu" "F.Mask" "F.Paste")
			(roundrect_rratio 0.25)
			(net 55 "/SoM_IO2/USB1.D+")
			(pintype "passive")
		)
		(pad "10" smd roundrect
			(at 0.385 -1 270)
			(size 0.25 0.55)
			(layers "F.Cu" "F.Mask" "F.Paste")
			(roundrect_rratio 0.25)
			(net 140 "/SoM_IO2/USB1.D-")
			(pintype "passive")
		)
	)
	(footprint "antmicro-footprints:R_0402_1005Metric"
		(layer "F.Cu")
		(at 179.45 138.95 180)
		(descr "Resistor SMD 0402")
		(tags "resistor SMD 0402")
		(property "Reference" "R12"
			(at 0.85 0.65 0)
			(layer "F.SilkS")
			(effects
				(font
					(size 0.7 0.7)
					(thickness 0.15)
				)
				(justify right top)
			)
		)
		(property "Value" "R_499k_0402"
			(at -1.011843 1.772047 0)
			(layer "F.Fab")
			(effects
				(font
					(size 0.7 0.7)
					(thickness 0.15)
				)
				(justify right top)
			)
		)
		(property "Datasheet" "https://www.mouser.com/datasheet/2/54/cr-1858361.pdf"
			(at 0 0 0)
			(layer "F.Fab")
			(hide yes)
			(effects
				(font
					(size 1.27 1.27)
					(thickness 0.15)
				)
			)
		)
		(property "Description" "SMD Chip Resistor, 499 kohm, ± 1%, 63 mW, 0402 [1005 Metric], Thick Film, General Purpose"
			(at 0 0 0)
			(layer "F.Fab")
			(hide yes)
			(effects
				(font
					(size 1.27 1.27)
					(thickness 0.15)
				)
			)
		)
		(property "MPN" "CR0402-FX-4993GLF"
			(at 0 0 180)
			(unlocked yes)
			(layer "F.Fab")
			(hide yes)
			(effects
				(font
					(size 1 1)
					(thickness 0.15)
				)
			)
		)
		(property "Manufacturer" "Bourns"
			(at 0 0 180)
			(unlocked yes)
			(layer "F.Fab")
			(hide yes)
			(effects
				(font
					(size 1 1)
					(thickness 0.15)
				)
			)
		)
		(property "License" "Apache-2.0"
			(at 0 0 180)
			(unlocked yes)
			(layer "F.Fab")
			(hide yes)
			(effects
				(font
					(size 1 1)
					(thickness 0.15)
				)
			)
		)
		(property "Author" "Antmicro"
			(at 0 0 180)
			(unlocked yes)
			(layer "F.Fab")
			(hide yes)
			(effects
				(font
					(size 1 1)
					(thickness 0.15)
				)
			)
		)
		(property "Val" "499k"
			(at 0 0 180)
			(unlocked yes)
			(layer "F.Fab")
			(hide yes)
			(effects
				(font
					(size 1 1)
					(thickness 0.15)
				)
			)
		)
		(property "Tolerance" "1%"
			(at 0 0 180)
			(unlocked yes)
			(layer "F.Fab")
			(hide yes)
			(effects
				(font
					(size 1 1)
					(thickness 0.15)
				)
			)
		)
		(sheetname "/DCDC/")
		(sheetfile "dcdc.kicad_sch")
		(attr smd exclude_from_pos_files exclude_from_bom dnp)
		(fp_rect
			(start -0.925 -0.47)
			(end 0.925 0.47)
			(stroke
				(width 0.05)
				(type default)
			)
			(fill no)
			(layer "F.CrtYd")
		)
		(fp_rect
			(start -0.5 -0.25)
			(end 0.5 0.25)
			(stroke
				(width 0.15)
				(type solid)
			)
			(fill no)
			(layer "F.Fab")
		)
		(fp_text user "Author: Antmicro"
			(at -0.95 4.169 0)
			(layer "F.Fab")
			(effects
				(font
					(size 0.7 0.7)
					(thickness 0.15)
				)
				(justify right top)
			)
		)
		(fp_text user "${REFERENCE}"
			(at -0.95 3.168 0)
			(layer "F.Fab")
			(effects
				(font
					(size 0.7 0.7)
					(thickness 0.15)
				)
				(justify right top)
			)
		)
		(fp_text user "License: Apache-2.0"
			(at -0.95 5.169 0)
			(layer "F.Fab")
			(effects
				(font
					(size 0.7 0.7)
					(thickness 0.15)
				)
				(justify right top)
			)
		)
		(pad "1" smd roundrect
			(at -0.48 0 180)
			(size 0.59 0.64)
			(layers "F.Cu" "F.Mask" "F.Paste")
			(roundrect_rratio 0.25)
			(net 1204 "/DCDC/12V_MODE1")
			(pintype "passive")
		)
		(pad "2" smd roundrect
			(at 0.48 0 180)
			(size 0.59 0.64)
			(layers "F.Cu" "F.Mask" "F.Paste")
			(roundrect_rratio 0.25)
			(net 20 "/DCDC/12V_VDD")
			(pintype "passive")
		)
	)
	(footprint "antmicro-footprints:DFN-6-1EP_3x2mm_P0.5mm_EP1.65x1.35mm"
		(layer "F.Cu")
		(at 97.7 59.35 -90)
		(property "Reference" "U3"
			(at -0.8 -1.45 90)
			(layer "F.SilkS")
			(effects
				(font
					(size 0.7 0.7)
					(thickness 0.15)
				)
				(justify right top)
			)
		)
		(property "Value" "LTC6994CDCB-1_DFN"
			(at -1.1 2.2 90)
			(layer "F.Fab")
			(effects
				(font
					(size 0.7 0.7)
					(thickness 0.15)
				)
				(justify right top)
			)
		)
		(property "Datasheet" "https://www.analog.com/media/en/technical-documentation/data-sheets/699412fb.pdf"
			(at 0 0 90)
			(layer "F.Fab")
			(hide yes)
			(effects
				(font
					(size 1.27 1.27)
					(thickness 0.15)
				)
			)
		)
		(property "Description" "Programmable delay block"
			(at 0 0 90)
			(layer "F.Fab")
			(hide yes)
			(effects
				(font
					(size 1.27 1.27)
					(thickness 0.15)
				)
			)
		)
		(property "MPN" "LTC6994CDCB-1#TRMPBF"
			(at 0 0 270)
			(unlocked yes)
			(layer "F.Fab")
			(hide yes)
			(effects
				(font
					(size 1 1)
					(thickness 0.15)
				)
			)
		)
		(property "Manufacturer" "Analog Devices"
			(at 0 0 270)
			(unlocked yes)
			(layer "F.Fab")
			(hide yes)
			(effects
				(font
					(size 1 1)
					(thickness 0.15)
				)
			)
		)
		(property "Author" "Antmicro"
			(at 0 0 270)
			(unlocked yes)
			(layer "F.Fab")
			(hide yes)
			(effects
				(font
					(size 1 1)
					(thickness 0.15)
				)
			)
		)
		(property "License" "Apache-2.0"
			(at 0 0 270)
			(unlocked yes)
			(layer "F.Fab")
			(hide yes)
			(effects
				(font
					(size 1 1)
					(thickness 0.15)
				)
			)
		)
		(sheetname "/SoM_Power/")
		(sheetfile "som_power.kicad_sch")
		(attr smd)
		(fp_line
			(start -1.5 1.1)
			(end 1.5 1.1)
			(stroke
				(width 0.15)
				(type solid)
			)
			(layer "F.SilkS")
		)
		(fp_line
			(start 0 -1.1)
			(end 1.5 -1.1)
			(stroke
				(width 0.15)
				(type solid)
			)
			(layer "F.SilkS")
		)
		(fp_circle
			(center -1.7 -0.9)
			(end -1.65 -0.9)
			(stroke
				(width 0.15)
				(type solid)
			)
			(fill yes)
			(layer "F.SilkS")
		)
		(fp_rect
			(start -1.9 -1.25)
			(end 1.9 1.25)
			(stroke
				(width 0.05)
				(type solid)
			)
			(fill no)
			(layer "F.CrtYd")
		)
		(fp_line
			(start -1.5 1)
			(end -1.5 -0.5)
			(stroke
				(width 0.15)
				(type solid)
			)
			(layer "F.Fab")
		)
		(fp_line
			(start 1.5 1)
			(end -1.5 1)
			(stroke
				(width 0.15)
				(type solid)
			)
			(layer "F.Fab")
		)
		(fp_line
			(start -1.5 -0.5)
			(end -1 -1)
			(stroke
				(width 0.15)
				(type solid)
			)
			(layer "F.Fab")
		)
		(fp_line
			(start -1 -1)
			(end 1.5 -1)
			(stroke
				(width 0.15)
				(type solid)
			)
			(layer "F.Fab")
		)
		(fp_line
			(start 1.5 -1)
			(end 1.5 1)
			(stroke
				(width 0.15)
				(type solid)
			)
			(layer "F.Fab")
		)
		(fp_text user "${REFERENCE}"
			(at -2.45 3.95 90)
			(layer "F.Fab")
			(effects
				(font
					(size 0.7 0.7)
					(thickness 0.15)
				)
				(justify right top)
			)
		)
		(fp_text user "License: Apache-2.0"
			(at -2.45 6.35 90)
			(layer "F.Fab")
			(effects
				(font
					(size 0.7 0.7)
					(thickness 0.15)
				)
				(justify right top)
			)
		)
		(fp_text user "Author: Antmicro"
			(at -2.45 5.15 90)
			(layer "F.Fab")
			(effects
				(font
					(size 0.7 0.7)
					(thickness 0.15)
				)
				(justify right top)
			)
		)
		(pad "" smd roundrect
			(at -0.41 -0.34 270)
			(size 0.67 0.54)
			(layers "F.Paste")
			(roundrect_rratio 0.25)
		)
		(pad "" smd roundrect
			(at -0.41 0.34 270)
			(size 0.67 0.54)
			(layers "F.Paste")
			(roundrect_rratio 0.25)
		)
		(pad "" smd roundrect
			(at 0.41 -0.34 270)
			(size 0.67 0.54)
			(layers "F.Paste")
			(roundrect_rratio 0.25)
		)
		(pad "" smd roundrect
			(at 0.41 0.34 270)
			(size 0.67 0.54)
			(layers "F.Paste")
			(roundrect_rratio 0.25)
		)
		(pad "1" smd rect
			(at -1.425 -0.5 270)
			(size 0.7 0.25)
			(layers "F.Cu" "F.Mask" "F.Paste")
			(net 4 "+3V3_AON")
			(pinfunction "V+")
			(pintype "power_in")
		)
		(pad "2" smd rect
			(at -1.425 0 270)
			(size 0.7 0.25)
			(layers "F.Cu" "F.Mask" "F.Paste")
			(net 1380 "Net-(U3-DIV)")
			(pinfunction "DIV")
			(pintype "input")
		)
		(pad "3" smd rect
			(at -1.425 0.5 270)
			(size 0.7 0.25)
			(layers "F.Cu" "F.Mask" "F.Paste")
			(net 1381 "Net-(U3-SET)")
			(pinfunction "SET")
			(pintype "passive")
		)
		(pad "4" smd rect
			(at 1.425 0.5 270)
			(size 0.7 0.25)
			(layers "F.Cu" "F.Mask" "F.Paste")
			(net 1287 "/SoM_Power/MODULE_POWER_ON")
			(pinfunction "IN")
			(pintype "input")
		)
		(pad "5" smd rect
			(at 1.425 0 270)
			(size 0.7 0.25)
			(layers "F.Cu" "F.Mask" "F.Paste")
			(net 1 "GND")
			(pinfunction "GND")
			(pintype "power_in")
		)
		(pad "6" smd rect
			(at 1.425 -0.5 270)
			(size 0.7 0.25)
			(layers "F.Cu" "F.Mask" "F.Paste")
			(net 1235 "Net-(Q30-S)")
			(pinfunction "OUT")
			(pintype "output")
		)
		(pad "7" smd rect
			(at 0 0 270)
			(size 1.65 1.35)
			(layers "F.Cu" "F.Mask")
			(net 1 "GND")
			(pinfunction "EP")
			(pintype "passive")
		)
	)
	(footprint "antmicro-footprints:R_0402_1005Metric"
		(layer "F.Cu")
		(at 91.5 147.75 -90)
		(descr "Resistor SMD 0402")
		(tags "resistor SMD 0402")
		(property "Reference" "R191"
			(at -3.745 0.34 90)
			(layer "F.SilkS")
			(effects
				(font
					(size 0.7 0.7)
					(thickness 0.15)
				)
				(justify right top)
			)
		)
		(property "Value" "R_49R9_0402"
			(at -1.011843 1.772046 90)
			(layer "F.Fab")
			(effects
				(font
					(size 0.7 0.7)
					(thickness 0.15)
				)
				(justify right top)
			)
		)
		(property "Datasheet" "https://www.bourns.com/docs/product-datasheets/cr.pdf"
			(at 0 0 90)
			(layer "F.Fab")
			(hide yes)
			(effects
				(font
					(size 1.27 1.27)
					(thickness 0.15)
				)
			)
		)
		(property "Description" "SMD Chip Resistor, 49.9 ohm, ± 1%, 62.5 mW, 0402 [1005 Metric], Thick Film, General Purpose"
			(at 0 0 90)
			(layer "F.Fab")
			(hide yes)
			(effects
				(font
					(size 1.27 1.27)
					(thickness 0.15)
				)
			)
		)
		(property "MPN" "CR0402-FX-49R9GLF"
			(at 0 0 270)
			(unlocked yes)
			(layer "F.Fab")
			(hide yes)
			(effects
				(font
					(size 1 1)
					(thickness 0.15)
				)
			)
		)
		(property "Manufacturer" "Bourns"
			(at 0 0 270)
			(unlocked yes)
			(layer "F.Fab")
			(hide yes)
			(effects
				(font
					(size 1 1)
					(thickness 0.15)
				)
			)
		)
		(property "License" "Apache-2.0"
			(at 0 0 270)
			(unlocked yes)
			(layer "F.Fab")
			(hide yes)
			(effects
				(font
					(size 1 1)
					(thickness 0.15)
				)
			)
		)
		(property "Author" "Antmicro"
			(at 0 0 270)
			(unlocked yes)
			(layer "F.Fab")
			(hide yes)
			(effects
				(font
					(size 1 1)
					(thickness 0.15)
				)
			)
		)
		(property "Val" "49R9"
			(at 0 0 270)
			(unlocked yes)
			(layer "F.Fab")
			(hide yes)
			(effects
				(font
					(size 1 1)
					(thickness 0.15)
				)
			)
		)
		(property "Tolerance" "1%"
			(at 0 0 270)
			(unlocked yes)
			(layer "F.Fab")
			(hide yes)
			(effects
				(font
					(size 1 1)
					(thickness 0.15)
				)
			)
		)
		(sheetname "/SoM_IO2/")
		(sheetfile "som_io2.kicad_sch")
		(attr smd)
		(fp_poly
			(pts
				(xy -0.925 -0.47) (xy 0.925 -0.47) (xy 0.925 0.47) (xy -0.925 0.47)
			)
			(stroke
				(width 0.05)
				(type default)
			)
			(fill no)
			(layer "F.CrtYd")
		)
		(fp_poly
			(pts
				(xy -0.5 -0.25) (xy 0.5 -0.25) (xy 0.5 0.25) (xy -0.5 0.25)
			)
			(stroke
				(width 0.15)
				(type solid)
			)
			(fill no)
			(layer "F.Fab")
		)
		(fp_text user "License: Apache-2.0"
			(at -0.949999 5.169 90)
			(layer "F.Fab")
			(effects
				(font
					(size 0.7 0.7)
					(thickness 0.15)
				)
				(justify right top)
			)
		)
		(fp_text user "${REFERENCE}"
			(at -0.95 3.168 90)
			(layer "F.Fab")
			(effects
				(font
					(size 0.7 0.7)
					(thickness 0.15)
				)
				(justify right top)
			)
		)
		(fp_text user "Author: Antmicro"
			(at -0.95 4.169 90)
			(layer "F.Fab")
			(effects
				(font
					(size 0.7 0.7)
					(thickness 0.15)
				)
				(justify right top)
			)
		)
		(pad "1" smd roundrect
			(at -0.48 0 270)
			(size 0.59 0.64)
			(layers "F.Cu" "F.Mask" "F.Paste")
			(roundrect_rratio 0.25)
			(net 1 "GND")
			(pintype "passive")
		)
		(pad "2" smd roundrect
			(at 0.48 0 270)
			(size 0.59 0.64)
			(layers "F.Cu" "F.Mask" "F.Paste")
			(roundrect_rratio 0.25)
			(net 1002 "/SoM_IO2/C2_REFCLK-")
			(pintype "passive")
		)
	)
)
